# TIMECARD (Time Appliance Project (Time Card)) — schematic netlist excerpt (pin names and nets, part order shuffled) for the footprints in the layout excerpt that follows; sources: Cadence DE-HDL packaged netlist, KiCad conversion of R4006-B0001-02_R01.brd

R258  RESISTOR  330OHM 1%  pkg SMC_0402R_H016  page 26 : \1\ = UNNAMED_14_OPTICAL_I11_A ; \2\ = XP3R3V_FPGA
C56  CAPACITOR  0.1UF 25V 10%  pkg SMC_0402R_H022  page 28 : \1\ = UNNAMED_517_CAPACITOR_I27_1 ; \2\ = XP3R3V_SW

(kicad_pcb
	(version 20260206)
	(generator "pcbnew")
	(generator_version "10.0")
	(general
		(thickness 1.6)
		(legacy_teardrops no)
	)
	(paper "A4")
	(title_block
		(title "timecard-production-celestica-r4006 — R4006-B0001-02_R01.brd")
		(comment 1 "Time Appliance Project (Time Card) / footprints 853-854 of 1113")
	)
	(layers
		(0 "F.Cu" signal "TOP")
		(4 "In1.Cu" signal "L02_GND1")
		(6 "In2.Cu" signal "L03_SIG1")
		(8 "In3.Cu" signal "L04_GND2")
		(10 "In4.Cu" signal "L05_VCC1")
		(12 "In5.Cu" signal "L06_VCC2")
		(14 "In6.Cu" signal "L07_GND3")
		(16 "In7.Cu" signal "L08_SIG2")
		(18 "In8.Cu" signal "L09_GND4")
		(2 "B.Cu" signal "BOTTOM")
		(9 "F.Adhes" user "F.Adhesive")
		(11 "B.Adhes" user "B.Adhesive")
		(13 "F.Paste" user "Package Geometry/Pastemask Top")
		(15 "B.Paste" user "Package Geometry/Pastemask Bottom")
		(5 "F.SilkS" user "Ref Des/Silkscreen Top")
		(7 "B.SilkS" user "Ref Des/Silkscreen Bottom")
		(1 "F.Mask" user "Board Geometry/Soldermask Top")
		(3 "B.Mask" user "Board Geometry/Soldermask Bottom")
		(17 "Dwgs.User" user "User.Drawings")
		(19 "Cmts.User" user "User.Comments")
		(21 "Eco1.User" user "User.Eco1")
		(23 "Eco2.User" user "User.Eco2")
		(25 "Edge.Cuts" user "Board Geometry/Outline")
		(27 "Margin" user)
		(31 "F.CrtYd" user "Package Geometry/Place Bound Top")
		(29 "B.CrtYd" user "Package Geometry/Place Bound Bottom")
		(35 "F.Fab" user "Ref Des/Assembly Top")
		(33 "B.Fab" user "Ref Des/Assembly Bottom")
	)
	(footprint ""
		(layer "B.Cu")
		(at 141.097 -107.696 90)
		(property "Reference" "R258"
			(at -0.762 1.03505 270)
			(unlocked yes)
			(layer "B.SilkS")
			(effects
				(font
					(size 0.635 0.4064)
					(thickness 0.1524)
				)
				(justify mirror)
			)
		)
		(property "Value" "VAL*"
			(at -0.02032 2.13233 90)
			(unlocked yes)
			(layer "B.Fab")
			(hide yes)
			(effects
				(font
					(size 0.7874 0.5842)
					(thickness 0.1524)
				)
				(justify mirror)
			)
		)
		(property "Device Type" "RESISTOR-G155-13300-01,330OHM,A"
			(at -0.008382 1.210564 90)
			(unlocked yes)
			(layer "B.Fab")
			(hide yes)
			(effects
				(font
					(size 0.7874 0.5842)
					(thickness 0.1524)
				)
				(justify mirror)
			)
		)
		(property "User Part Number" "PARTNUM*"
			(at -0.02032 4.024884 90)
			(unlocked yes)
			(layer "Cmts.User")
			(hide yes)
			(effects
				(font
					(size 0.7874 0.5842)
					(thickness 0.1524)
				)
				(justify mirror)
			)
		)
		(property "Tolerance" "TOL*"
			(at -0.044704 3.05435 90)
			(unlocked yes)
			(layer "Cmts.User")
			(hide yes)
			(effects
				(font
					(size 0.7874 0.5842)
					(thickness 0.1524)
				)
				(justify mirror)
			)
		)
		(duplicate_pad_numbers_are_jumpers no)
		(fp_line
			(start 1.143 -0.5588)
			(end 1.143 0.5588)
			(stroke
				(width 0.1)
				(type default)
			)
			(layer "B.SilkS")
		)
		(fp_line
			(start -1.143 -0.5588)
			(end 1.143 -0.5588)
			(stroke
				(width 0.1)
				(type default)
			)
			(layer "B.SilkS")
		)
		(fp_line
			(start 1.143 0.5588)
			(end -1.143 0.5588)
			(stroke
				(width 0.1)
				(type default)
			)
			(layer "B.SilkS")
		)
		(fp_line
			(start -1.143 0.5588)
			(end -1.143 -0.5588)
			(stroke
				(width 0.1)
				(type default)
			)
			(layer "B.SilkS")
		)
		(fp_rect
			(start -1.143 -0.5588)
			(end 1.143 0.5588)
			(stroke
				(width 0)
				(type default)
			)
			(fill no)
			(layer "B.CrtYd")
		)
		(fp_line
			(start 0.508 -0.3048)
			(end 0.508 0.3048)
			(stroke
				(width 0.1)
				(type default)
			)
			(layer "B.Fab")
		)
		(fp_line
			(start -0.508 -0.3048)
			(end 0.508 -0.3048)
			(stroke
				(width 0.1)
				(type default)
			)
			(layer "B.Fab")
		)
		(fp_line
			(start 0.508 0.3048)
			(end -0.508 0.3048)
			(stroke
				(width 0.1)
				(type default)
			)
			(layer "B.Fab")
		)
		(fp_line
			(start -0.508 0.3048)
			(end -0.508 -0.3048)
			(stroke
				(width 0.1)
				(type default)
			)
			(layer "B.Fab")
		)
		(pad "1" smd rect
			(at 0.5334 0 270)
			(size 0.7112 0.6096)
			(layers "B.Cu" "B.Mask" "B.Paste")
			(net "UNNAMED_14_OPTICAL_I11_A")
		)
		(pad "2" smd rect
			(at -0.5334 0 270)
			(size 0.7112 0.6096)
			(layers "B.Cu" "B.Mask" "B.Paste")
			(net "XP3R3V_FPGA")
		)
		(zone
			(layer "B.Cu")
			(hatch none 0.5)
			(connect_pads
				(clearance 0)
			)
			(min_thickness 0.25)
			(keepout
				(tracks allowed)
				(vias not_allowed)
				(pads allowed)
				(copperpour not_allowed)
				(footprints allowed)
			)
			(placement
				(enabled no)
				(sheetname "")
			)
			(fill
				(thermal_gap 0.5)
				(thermal_bridge_width 0.5)
				(island_removal_mode 0)
			)
			(polygon
				(pts
					(xy 140.7922 -107.6198) (xy 141.4018 -107.6198) (xy 141.4018 -107.7722) (xy 140.7922 -107.7722)
				)
			)
		)
	)
	(footprint ""
		(layer "B.Cu")
		(at 82.931 -103.378)
		(property "Reference" "C56"
			(at -2.413 0.03937 0)
			(unlocked yes)
			(layer "B.SilkS")
			(effects
				(font
					(size 0.7874 0.5842)
					(thickness 0.1524)
				)
				(justify mirror)
			)
		)
		(property "Value" "VAL*"
			(at -0.0762 2.067306 0)
			(unlocked yes)
			(layer "B.Fab")
			(hide yes)
			(effects
				(font
					(size 0.7874 0.5842)
					(thickness 0.1524)
				)
				(justify mirror)
			)
		)
		(property "Tolerance" "TOL*"
			(at -0.0762 3.032506 0)
			(unlocked yes)
			(layer "Cmts.User")
			(hide yes)
			(effects
				(font
					(size 0.7874 0.5842)
					(thickness 0.1524)
				)
				(justify mirror)
			)
		)
		(property "User Part Number" "PARTNUM*"
			(at -0.1016 4.023106 0)
			(unlocked yes)
			(layer "Cmts.User")
			(hide yes)
			(effects
				(font
					(size 0.7874 0.5842)
					(thickness 0.1524)
				)
				(justify mirror)
			)
		)
		(property "Device Type" "CAPACITOR-G105-0B104-EK,0.1UF,A"
			(at -0.0508 1.127506 0)
			(unlocked yes)
			(layer "B.Fab")
			(hide yes)
			(effects
				(font
					(size 0.7874 0.5842)
					(thickness 0.1524)
				)
				(justify mirror)
			)
		)
		(duplicate_pad_numbers_are_jumpers no)
		(fp_line
			(start -1.143 -0.5588)
			(end 1.143 -0.5588)
			(stroke
				(width 0.1)
				(type default)
			)
			(layer "B.SilkS")
		)
		(fp_line
			(start -1.143 0.5588)
			(end -1.143 -0.5588)
			(stroke
				(width 0.1)
				(type default)
			)
			(layer "B.SilkS")
		)
		(fp_line
			(start 1.143 -0.5588)
			(end 1.143 0.5588)
			(stroke
				(width 0.1)
				(type default)
			)
			(layer "B.SilkS")
		)
		(fp_line
			(start 1.143 0.5588)
			(end -1.143 0.5588)
			(stroke
				(width 0.1)
				(type default)
			)
			(layer "B.SilkS")
		)
		(fp_rect
			(start 1.143 0.5588)
			(end -1.143 -0.5588)
			(stroke
				(width 0)
				(type default)
			)
			(fill no)
			(layer "B.CrtYd")
		)
		(fp_line
			(start -0.508 -0.3048)
			(end 0.508 -0.3048)
			(stroke
				(width 0.1)
				(type default)
			)
			(layer "B.Fab")
		)
		(fp_line
			(start -0.508 0.3048)
			(end -0.508 -0.3048)
			(stroke
				(width 0.1)
				(type default)
			)
			(layer "B.Fab")
		)
		(fp_line
			(start 0.508 -0.3048)
			(end 0.508 0.3048)
			(stroke
				(width 0.1)
				(type default)
			)
			(layer "B.Fab")
		)
		(fp_line
			(start 0.508 0.3048)
			(end -0.508 0.3048)
			(stroke
				(width 0.1)
				(type default)
			)
			(layer "B.Fab")
		)
		(pad "1" smd rect
			(at 0.5334 0 180)
			(size 0.7112 0.6096)
			(layers "B.Cu" "B.Mask" "B.Paste")
			(net "UNNAMED_517_CAPACITOR_I27_1")
		)
		(pad "2" smd rect
			(at -0.5334 0 180)
			(size 0.7112 0.6096)
			(layers "B.Cu" "B.Mask" "B.Paste")
			(net "XP3R3V_SW")
		)
		(zone
			(layer "B.Cu")
			(hatch none 0.5)
			(connect_pads
				(clearance 0)
			)
			(min_thickness 0.25)
			(keepout
				(tracks allowed)
				(vias not_allowed)
				(pads allowed)
				(copperpour not_allowed)
				(footprints allowed)
			)
			(placement
				(enabled no)
				(sheetname "")
			)
			(fill
				(thermal_gap 0.5)
				(thermal_bridge_width 0.5)
				(island_removal_mode 0)
			)
			(polygon
				(pts
					(xy 83.0072 -103.0732) (xy 83.0072 -103.6828) (xy 82.8548 -103.6828) (xy 82.8548 -103.0732)
				)
			)
		)
	)
)
